(kicad_pcb
	(version 20260206)
	(generator "pcbnew")
	(generator_version "10.0")
	(general
		(thickness 1.6)
		(legacy_teardrops no)
	)
	(paper "A4")
	(title_block
		(title "Bryce Canyon_F.DPB_16315-1-OCP.brd")
		(comment 1 "Bryce Canyon / footprints 756-758 of 2223")
	)
	(layers
		(0 "F.Cu" signal "TOP")
		(4 "In1.Cu" signal "L2GND")
		(6 "In2.Cu" signal "L3")
		(8 "In3.Cu" signal "L4GND")
		(10 "In4.Cu" signal "L5")
		(12 "In5.Cu" signal "L6VCC")
		(14 "In6.Cu" signal "L7VCC")
		(16 "In7.Cu" signal "L8")
		(18 "In8.Cu" signal "L9GND")
		(20 "In9.Cu" signal "L10")
		(22 "In10.Cu" signal "L11GND")
		(2 "B.Cu" signal "BOTTOM")
		(9 "F.Adhes" user "F.Adhesive")
		(11 "B.Adhes" user "B.Adhesive")
		(13 "F.Paste" user "Package Geometry/Pastemask Top")
		(15 "B.Paste" user "Package Geometry/Pastemask Bottom")
		(5 "F.SilkS" user "Ref Des/Silkscreen Top")
		(7 "B.SilkS" user "Ref Des/Silkscreen Bottom")
		(1 "F.Mask" user "Board Geometry/Soldermask Top")
		(3 "B.Mask" user "Board Geometry/Soldermask Bottom")
		(17 "Dwgs.User" user "User.Drawings")
		(19 "Cmts.User" user "User.Comments")
		(21 "Eco1.User" user "User.Eco1")
		(23 "Eco2.User" user "User.Eco2")
		(25 "Edge.Cuts" user "Board Geometry/Outline")
		(27 "Margin" user)
		(31 "F.CrtYd" user "Package Geometry/Place Bound Top")
		(29 "B.CrtYd" user "Package Geometry/Place Bound Bottom")
		(35 "F.Fab" user "Ref Des/Assembly Top")
		(33 "B.Fab" user "Ref Des/Assembly Bottom")
	)
	(footprint ""
		(layer "F.Cu")
		(at 465.622132 -130.368294 -90)
		(property "Reference" "R547"
			(at 0 0 270)
			(layer "F.SilkS")
			(hide yes)
			(effects
				(font
					(size 1.27 1.27)
				)
			)
		)
		(property "Value" "4K7R2J-2-GP"
			(at 0.064008 -3.993896 270)
			(unlocked yes)
			(layer "F.Fab")
			(hide yes)
			(effects
				(font
					(size 1.016 1.016)
					(thickness 0.1524)
				)
			)
		)
		(property "Device Type" "R402H16"
			(at 0.064008 -5.517896 270)
			(unlocked yes)
			(layer "F.Fab")
			(hide yes)
			(effects
				(font
					(size 1.016 1.016)
					(thickness 0.1524)
				)
			)
		)
		(duplicate_pad_numbers_are_jumpers no)
		(fp_line
			(start -0.508 -0.9398)
			(end -0.508 0.9398)
			(stroke
				(width 0.1524)
				(type default)
			)
			(layer "F.SilkS")
		)
		(fp_line
			(start 0.508 -0.9398)
			(end -0.508 -0.9398)
			(stroke
				(width 0.1524)
				(type default)
			)
			(layer "F.SilkS")
		)
		(fp_rect
			(start -0.508 0.9398)
			(end 0.508 -0.9398)
			(stroke
				(width 0)
				(type default)
			)
			(fill no)
			(layer "F.CrtYd")
		)
		(fp_rect
			(start -0.508 0.9398)
			(end 0.508 -0.9398)
			(stroke
				(width 0)
				(type default)
			)
			(fill no)
			(layer "F.Fab")
		)
		(pad "1" smd custom
			(at 0 -0.4445 270)
			(size 0.1397 0.1397)
			(layers "F.Cu" "F.Mask" "F.Paste")
			(net "DRIVE_A_23_ACT")
			(options
				(clearance outline)
				(anchor circle)
			)
			(primitives
				(gr_poly
					(pts
						(arc
							(start -0.1778 -0.2794)
							(mid -0.249642 -0.249642)
							(end -0.2794 -0.1778)
						)
						(arc
							(start -0.2794 0.1778)
							(mid -0.249642 0.249642)
							(end -0.1778 0.2794)
						)
						(arc
							(start 0.1778 0.2794)
							(mid 0.249642 0.249642)
							(end 0.2794 0.1778)
						)
						(arc
							(start 0.2794 -0.1778)
							(mid 0.249642 -0.249642)
							(end 0.1778 -0.2794)
						)
					)
					(width 0)
					(fill yes)
				)
			)
		)
		(pad "2" smd custom
			(at 0 0.4445 270)
			(size 0.1397 0.1397)
			(layers "F.Cu" "F.Mask" "F.Paste")
			(net "GND")
			(options
				(clearance outline)
				(anchor circle)
			)
			(primitives
				(gr_poly
					(pts
						(arc
							(start -0.1778 -0.2794)
							(mid -0.249642 -0.249642)
							(end -0.2794 -0.1778)
						)
						(arc
							(start -0.2794 0.1778)
							(mid -0.249642 0.249642)
							(end -0.1778 0.2794)
						)
						(arc
							(start 0.1778 0.2794)
							(mid 0.249642 0.249642)
							(end 0.2794 0.1778)
						)
						(arc
							(start 0.2794 -0.1778)
							(mid 0.249642 -0.249642)
							(end 0.1778 -0.2794)
						)
					)
					(width 0)
					(fill yes)
				)
			)
		)
	)
	(footprint ""
		(layer "F.Cu")
		(at 174.5742 -167.110918 90)
		(property "Reference" "R528"
			(at 0 0 90)
			(layer "F.SilkS")
			(hide yes)
			(effects
				(font
					(size 1.27 1.27)
				)
			)
		)
		(property "Value" "4K7R2J-2-GP"
			(at 0.064008 -3.993896 90)
			(unlocked yes)
			(layer "F.Fab")
			(hide yes)
			(effects
				(font
					(size 1.016 1.016)
					(thickness 0.1524)
				)
			)
		)
		(property "Device Type" "R402H16"
			(at 0.064008 -5.517896 90)
			(unlocked yes)
			(layer "F.Fab")
			(hide yes)
			(effects
				(font
					(size 1.016 1.016)
					(thickness 0.1524)
				)
			)
		)
		(duplicate_pad_numbers_are_jumpers no)
		(fp_line
			(start 0.508 -0.9398)
			(end -0.508 -0.9398)
			(stroke
				(width 0.1524)
				(type default)
			)
			(layer "F.SilkS")
		)
		(fp_line
			(start -0.508 -0.9398)
			(end -0.508 0.9398)
			(stroke
				(width 0.1524)
				(type default)
			)
			(layer "F.SilkS")
		)
		(fp_rect
			(start -0.508 0.9398)
			(end 0.508 -0.9398)
			(stroke
				(width 0)
				(type default)
			)
			(fill no)
			(layer "F.CrtYd")
		)
		(fp_rect
			(start -0.508 0.9398)
			(end 0.508 -0.9398)
			(stroke
				(width 0)
				(type default)
			)
			(fill no)
			(layer "F.Fab")
		)
		(pad "1" smd custom
			(at 0 -0.4445 90)
			(size 0.1397 0.1397)
			(layers "F.Cu" "F.Mask" "F.Paste")
			(net "P12V_A")
			(options
				(clearance outline)
				(anchor circle)
			)
			(primitives
				(gr_poly
					(pts
						(arc
							(start -0.1778 -0.2794)
							(mid -0.249642 -0.249642)
							(end -0.2794 -0.1778)
						)
						(arc
							(start -0.2794 0.1778)
							(mid -0.249642 0.249642)
							(end -0.1778 0.2794)
						)
						(arc
							(start 0.1778 0.2794)
							(mid 0.249642 0.249642)
							(end 0.2794 0.1778)
						)
						(arc
							(start 0.2794 -0.1778)
							(mid 0.249642 -0.249642)
							(end 0.1778 -0.2794)
						)
					)
					(width 0)
					(fill yes)
				)
			)
		)
		(pad "2" smd custom
			(at 0 0.4445 90)
			(size 0.1397 0.1397)
			(layers "F.Cu" "F.Mask" "F.Paste")
			(net "SW_HDD_P17")
			(options
				(clearance outline)
				(anchor circle)
			)
			(primitives
				(gr_poly
					(pts
						(arc
							(start -0.1778 -0.2794)
							(mid -0.249642 -0.249642)
							(end -0.2794 -0.1778)
						)
						(arc
							(start -0.2794 0.1778)
							(mid -0.249642 0.249642)
							(end -0.1778 0.2794)
						)
						(arc
							(start 0.1778 0.2794)
							(mid 0.249642 0.249642)
							(end 0.2794 0.1778)
						)
						(arc
							(start 0.2794 -0.1778)
							(mid 0.249642 -0.249642)
							(end 0.1778 -0.2794)
						)
					)
					(width 0)
					(fill yes)
				)
			)
		)
	)
	(footprint ""
		(layer "F.Cu")
		(at 420.200074 -287.910016 -90)
		(property "Reference" "HDDSAS9"
			(at 0 0 270)
			(layer "F.SilkS")
			(hide yes)
			(effects
				(font
					(size 1.27 1.27)
				)
			)
		)
		(property "Value" "SKT-SAS15P-14P-45-GP"
			(at -20.7645 -8.9789 270)
			(unlocked yes)
			(layer "F.Fab")
			(hide yes)
			(effects
				(font
					(size 1.016 1.016)
					(thickness 0.1524)
				)
			)
		)
		(property "Device Type" "10120818-001C-TRLF"
			(at -20.7645 -10.5029 270)
			(unlocked yes)
			(layer "F.Fab")
			(hide yes)
			(effects
				(font
					(size 1.016 1.016)
					(thickness 0.1524)
				)
			)
		)
		(duplicate_pad_numbers_are_jumpers no)
		(fp_line
			(start 1.651 4.2926)
			(end 1.651 3.0099)
			(stroke
				(width 0.1524)
				(type default)
			)
			(layer "F.SilkS")
		)
		(fp_line
			(start 8.509 4.2926)
			(end 1.651 4.2926)
			(stroke
				(width 0.1524)
				(type default)
			)
			(layer "F.SilkS")
		)
		(fp_line
			(start -23.4188 3.0099)
			(end -23.4188 -3.2512)
			(stroke
				(width 0.1524)
				(type default)
			)
			(layer "F.SilkS")
		)
		(fp_line
			(start 1.651 3.0099)
			(end -23.4188 3.0099)
			(stroke
				(width 0.1524)
				(type default)
			)
			(layer "F.SilkS")
		)
		(fp_line
			(start 8.509 3.0099)
			(end 8.509 4.2926)
			(stroke
				(width 0.1524)
				(type default)
			)
			(layer "F.SilkS")
		)
		(fp_line
			(start 23.4188 3.0099)
			(end 8.509 3.0099)
			(stroke
				(width 0.1524)
				(type default)
			)
			(layer "F.SilkS")
		)
		(fp_line
			(start -23.4188 -3.2512)
			(end 23.4188 -3.2512)
			(stroke
				(width 0.1524)
				(type default)
			)
			(layer "F.SilkS")
		)
		(fp_line
			(start 23.4188 -3.2512)
			(end 23.4188 3.0099)
			(stroke
				(width 0.1524)
				(type default)
			)
			(layer "F.SilkS")
		)
		(fp_line
			(start 15.5067 -3.3401)
			(end 16.2687 -3.3401)
			(stroke
				(width 0.3302)
				(type default)
			)
			(layer "F.SilkS")
		)
		(fp_poly
			(pts
				(xy 15.868904 -3.230372) (xy 16.503904 -3.865372) (xy 15.233904 -3.865372)
			)
			(stroke
				(width 0)
				(type default)
			)
			(fill yes)
			(layer "F.SilkS")
		)
		(fp_poly
			(pts
				(xy -22.8727 -2.7559) (xy 22.8727 -2.7559) (xy 22.8727 2.7559) (xy 8.255 2.7559) (xy 8.255 3.5179)
				(xy 1.905 3.5179) (xy 1.905 2.7559) (xy -22.8727 2.7559)
			)
			(stroke
				(width 0)
				(type default)
			)
			(fill no)
			(layer "F.CrtYd")
		)
		(fp_poly
			(pts
				(xy 1.397 4.5466) (xy 1.397 3.2639) (xy -23.6728 3.2639) (xy -23.6728 -3.5052) (xy 23.6728 -3.5052)
				(xy 23.6728 -0.00635) (xy 22.8727 -0.00635) (xy 22.8727 -2.7559) (xy -22.8727 -2.7559) (xy -22.8727 2.7559)
				(xy 1.905 2.7559) (xy 1.905 3.5179) (xy 8.255 3.5179) (xy 8.255 2.7559) (xy 22.8727 2.7559) (xy 22.8727 0.00635)
				(xy 23.6728 0.00635) (xy 23.6728 3.2639) (xy 8.763 3.2639) (xy 8.763 4.5466)
			)
			(stroke
				(width 0)
				(type default)
			)
			(fill no)
			(layer "F.CrtYd")
		)
		(fp_poly
			(pts
				(xy 1.397 4.5466) (xy 1.397 3.2639) (xy -23.6728 3.2639) (xy -23.6728 -3.5052) (xy 23.6728 -3.5052)
				(xy 23.6728 3.2639) (xy 8.763 3.2639) (xy 8.763 4.5466)
			)
			(stroke
				(width 0)
				(type default)
			)
			(fill no)
			(layer "F.Fab")
		)
		(pad "" np_thru_hole circle
			(at -18.874994 0 270)
			(size 0.254 0.254)
			(drill 1.3462)
			(layers "*.Cu" "*.Mask")
			(clearance 0.9017)
			(thermal_gap 0.9017)
		)
		(pad "" np_thru_hole circle
			(at 18.874994 0 270)
			(size 0.254 0.254)
			(drill 0.9398)
			(layers "*.Cu" "*.Mask")
			(clearance 0.6985)
			(thermal_gap 0.6985)
		)
		(pad "G1" smd rect
			(at 21.874988 0 270)
			(size 2.5908 2.5908)
			(layers "F.Cu" "F.Mask" "F.Paste")
			(net "GND")
		)
		(pad "G2" smd rect
			(at -21.874988 0 270)
			(size 2.5908 2.5908)
			(layers "F.Cu" "F.Mask" "F.Paste")
			(net "GND")
		)
		(pad "P1" smd rect
			(at 1.905 -1.82499 270)
			(size 0.6096 2.3622)
			(layers "F.Cu" "F.Mask" "F.Paste")
			(net "Net_2171")
		)
		(pad "P2" smd rect
			(at 0.635 -1.82499 270)
			(size 0.6096 2.3622)
			(layers "F.Cu" "F.Mask" "F.Paste")
			(net "Net_2172")
		)
		(pad "P3" smd rect
			(at -0.635 -1.82499 270)
			(size 0.6096 2.3622)
			(layers "F.Cu" "F.Mask" "F.Paste")
			(net "Net_2173")
		)
		(pad "P4" smd rect
			(at -1.905 -1.82499 270)
			(size 0.6096 2.3622)
			(layers "F.Cu" "F.Mask" "F.Paste")
			(net "GND")
		)
		(pad "P5" smd rect
			(at -3.175 -1.82499 270)
			(size 0.6096 2.3622)
			(layers "F.Cu" "F.Mask" "F.Paste")
			(net "HDD_PRSNT_9")
		)
		(pad "P6" smd rect
			(at -4.445 -1.82499 270)
			(size 0.6096 2.3622)
			(layers "F.Cu" "F.Mask" "F.Paste")
			(net "GND")
		)
		(pad "P7" smd rect
			(at -5.715 -1.82499 270)
			(size 0.6096 2.3622)
			(layers "F.Cu" "F.Mask" "F.Paste")
			(net "5V_PRE_9")
		)
		(pad "P8" smd rect
			(at -6.985 -1.82499 270)
			(size 0.6096 2.3622)
			(layers "F.Cu" "F.Mask" "F.Paste")
			(net "P5V_HDD9")
		)
		(pad "P9" smd rect
			(at -8.255 -1.82499 270)
			(size 0.6096 2.3622)
			(layers "F.Cu" "F.Mask" "F.Paste")
			(net "P5V_HDD9")
		)
		(pad "P10" smd rect
			(at -9.525 -1.82499 270)
			(size 0.6096 2.3622)
			(layers "F.Cu" "F.Mask" "F.Paste")
			(net "GND")
		)
		(pad "P11" smd rect
			(at -10.795 -1.82499 270)
			(size 0.6096 2.3622)
			(layers "F.Cu" "F.Mask" "F.Paste")
			(net "ACT_HDD_9")
		)
		(pad "P12" smd rect
			(at -12.065 -1.82499 270)
			(size 0.6096 2.3622)
			(layers "F.Cu" "F.Mask" "F.Paste")
			(net "GND")
		)
		(pad "P13" smd rect
			(at -13.335 -1.82499 270)
			(size 0.6096 2.3622)
			(layers "F.Cu" "F.Mask" "F.Paste")
			(net "12V_PRE_9")
		)
		(pad "P14" smd rect
			(at -14.605 -1.82499 270)
			(size 0.6096 2.3622)
			(layers "F.Cu" "F.Mask" "F.Paste")
			(net "P12V_HDD9")
		)
		(pad "P15" smd rect
			(at -15.875 -1.82499 270)
			(size 0.6096 2.3622)
			(layers "F.Cu" "F.Mask" "F.Paste")
			(net "P12V_HDD9")
		)
		(pad "S1" smd rect
			(at 15.875 -1.82499 270)
			(size 0.6096 2.3622)
			(layers "F.Cu" "F.Mask" "F.Paste")
			(net "GND")
		)
		(pad "S2" smd rect
			(at 14.605 -1.82499 270)
			(size 0.6096 2.3622)
			(layers "F.Cu" "F.Mask" "F.Paste")
			(net "SAS_HDD_RX_P9")
		)
		(pad "S3" smd rect
			(at 13.335 -1.82499 270)
			(size 0.6096 2.3622)
			(layers "F.Cu" "F.Mask" "F.Paste")
			(net "SAS_HDD_RX_N9")
		)
		(pad "S4" smd rect
			(at 12.065 -1.82499 270)
			(size 0.6096 2.3622)
			(layers "F.Cu" "F.Mask" "F.Paste")
			(net "GND")
		)
		(pad "S5" smd rect
			(at 10.795 -1.82499 270)
			(size 0.6096 2.3622)
			(layers "F.Cu" "F.Mask" "F.Paste")
			(net "PHY_DRV_A_TO_SCC_A_9_DN")
		)
		(pad "S6" smd rect
			(at 9.525 -1.82499 270)
			(size 0.6096 2.3622)
			(layers "F.Cu" "F.Mask" "F.Paste")
			(net "PHY_DRV_A_TO_SCC_A_9_DP")
		)
		(pad "S7" smd rect
			(at 8.255 -1.82499 270)
			(size 0.6096 2.3622)
			(layers "F.Cu" "F.Mask" "F.Paste")
			(net "GND")
		)
		(pad "S8" smd rect
			(at 7.480046 2.845054 270)
			(size 0.508 2.3622)
			(layers "F.Cu" "F.Mask" "F.Paste")
			(net "GND")
		)
		(pad "S9" smd rect
			(at 6.679946 2.845054 270)
			(size 0.508 2.3622)
			(layers "F.Cu" "F.Mask" "F.Paste")
			(net "Net_446")
		)
		(pad "S10" smd rect
			(at 5.8801 2.845054 270)
			(size 0.508 2.3622)
			(layers "F.Cu" "F.Mask" "F.Paste")
			(net "Net_338")
		)
		(pad "S11" smd rect
			(at 5.08 2.845054 270)
			(size 0.508 2.3622)
			(layers "F.Cu" "F.Mask" "F.Paste")
			(net "GND")
		)
		(pad "S12" smd rect
			(at 4.2799 2.845054 270)
			(size 0.508 2.3622)
			(layers "F.Cu" "F.Mask" "F.Paste")
			(net "Net_374")
		)
		(pad "S13" smd rect
			(at 3.480054 2.845054 270)
			(size 0.508 2.3622)
			(layers "F.Cu" "F.Mask" "F.Paste")
			(net "Net_410")
		)
		(pad "S14" smd rect
			(at 2.679954 2.845054 270)
			(size 0.508 2.3622)
			(layers "F.Cu" "F.Mask" "F.Paste")
			(net "GND")
		)
		(zone
			(layer "F.Cu")
			(hatch none 0.5)
			(connect_pads
				(clearance 0)
			)
			(min_thickness 0.25)
			(keepout
				(tracks not_allowed)
				(vias allowed)
				(pads allowed)
				(copperpour not_allowed)
				(footprints allowed)
			)
			(placement
				(enabled no)
				(sheetname "")
			)
			(fill
				(thermal_gap 0.5)
				(thermal_bridge_width 0.5)
				(island_removal_mode 0)
			)
			(polygon
				(pts
					(xy 423.857674 -304.648616) (xy 416.783774 -304.648616) (xy 416.783774 -311.582816) (xy 417.888674 -311.582816)
					(xy 417.888674 -307.468016) (xy 422.511474 -307.468016) (xy 422.511474 -311.582816) (xy 423.857674 -311.582816)
				)
			)
		)
		(zone
			(layer "F.Cu")
			(hatch none 0.5)
			(connect_pads
				(clearance 0)
			)
			(min_thickness 0.25)
			(keepout
				(tracks allowed)
				(vias not_allowed)
				(pads allowed)
				(copperpour not_allowed)
				(footprints allowed)
			)
			(placement
				(enabled no)
				(sheetname "")
			)
			(fill
				(thermal_gap 0.5)
				(thermal_bridge_width 0.5)
				(island_removal_mode 0)
			)
			(polygon
				(pts
					(xy 423.857674 -304.648616) (xy 416.783774 -304.648616) (xy 416.783774 -311.582816) (xy 417.888674 -311.582816)
					(xy 417.888674 -307.468016) (xy 422.511474 -307.468016) (xy 422.511474 -311.582816) (xy 423.857674 -311.582816)
				)
			)
		)
		(zone
			(layer "F.Cu")
			(hatch none 0.5)
			(connect_pads
				(clearance 0)
			)
			(min_thickness 0.25)
			(keepout
				(tracks allowed)
				(vias not_allowed)
				(pads allowed)
				(copperpour not_allowed)
				(footprints allowed)
			)
			(placement
				(enabled no)
				(sheetname "")
			)
			(fill
				(thermal_gap 0.5)
				(thermal_bridge_width 0.5)
				(island_removal_mode 0)
			)
			(polygon
				(pts
					(xy 423.857674 -271.171416) (xy 416.783774 -271.171416) (xy 416.783774 -264.237216) (xy 417.888674 -264.237216)
					(xy 417.888674 -268.352016) (xy 422.511474 -268.352016) (xy 422.511474 -264.237216) (xy 423.857674 -264.237216)
				)
			)
		)
		(zone
			(layer "F.Cu")
			(hatch none 0.5)
			(connect_pads
				(clearance 0)
			)
			(min_thickness 0.25)
			(keepout
				(tracks not_allowed)
				(vias allowed)
				(pads allowed)
				(copperpour not_allowed)
				(footprints allowed)
			)
			(placement
				(enabled no)
				(sheetname "")
			)
			(fill
				(thermal_gap 0.5)
				(thermal_bridge_width 0.5)
				(island_removal_mode 0)
			)
			(polygon
				(pts
					(xy 423.857674 -271.171416) (xy 416.783774 -271.171416) (xy 416.783774 -264.237216) (xy 417.888674 -264.237216)
					(xy 417.888674 -268.352016) (xy 422.511474 -268.352016) (xy 422.511474 -264.237216) (xy 423.857674 -264.237216)
				)
			)
		)
		(zone
			(layers "F.Cu" "B.Cu" "In1.Cu" "In2.Cu" "In3.Cu" "In4.Cu" "In5.Cu" "In6.Cu"
				"In7.Cu" "In8.Cu" "In9.Cu" "In10.Cu"
			)
			(hatch none 0.5)
			(connect_pads
				(clearance 0)
			)
			(min_thickness 0.25)
			(keepout
				(tracks not_allowed)
				(vias allowed)
				(pads allowed)
				(copperpour not_allowed)
				(footprints allowed)
			)
			(placement
				(enabled no)
				(sheetname "")
			)
			(fill
				(thermal_gap 0.5)
				(thermal_bridge_width 0.5)
				(island_removal_mode 0)
			)
			(polygon
				(pts
					(arc
						(start 420.974774 -269.035022)
						(mid 419.425374 -269.035022)
						(end 420.974774 -269.035022)
					)
				)
			)
		)
		(zone
			(layers "F.Cu" "B.Cu" "In1.Cu" "In2.Cu" "In3.Cu" "In4.Cu" "In5.Cu" "In6.Cu"
				"In7.Cu" "In8.Cu" "In9.Cu" "In10.Cu"
			)
			(hatch none 0.5)
			(connect_pads
				(clearance 0)
			)
			(min_thickness 0.25)
			(keepout
				(tracks not_allowed)
				(vias allowed)
				(pads allowed)
				(copperpour not_allowed)
				(footprints allowed)
			)
			(placement
				(enabled no)
				(sheetname "")
			)
			(fill
				(thermal_gap 0.5)
				(thermal_bridge_width 0.5)
				(island_removal_mode 0)
			)
			(polygon
				(pts
					(arc
						(start 421.177974 -306.78501)
						(mid 419.222174 -306.78501)
						(end 421.177974 -306.78501)
					)
				)
			)
		)
	)
)
